(kicad_pcb
	(version 20260206)
	(generator "pcbnew")
	(generator_version "10.0")
	(general
		(thickness 1.6)
		(legacy_teardrops no)
	)
	(paper "A4")
	(title_block
		(title "Bryce Canyon_IOM_IOC_16318-2_OCP.brd")
		(comment 1 "Bryce Canyon / footprints 958-965 of 1605")
	)
	(layers
		(0 "F.Cu" signal "TOP")
		(4 "In1.Cu" signal "L2GND")
		(6 "In2.Cu" signal "L3")
		(8 "In3.Cu" signal "L4VCC")
		(10 "In4.Cu" signal "L5VCC")
		(12 "In5.Cu" signal "L6")
		(14 "In6.Cu" signal "L7GND")
		(2 "B.Cu" signal "BOTTOM")
		(9 "F.Adhes" user "F.Adhesive")
		(11 "B.Adhes" user "B.Adhesive")
		(13 "F.Paste" user "Package Geometry/Pastemask Top")
		(15 "B.Paste" user "Package Geometry/Pastemask Bottom")
		(5 "F.SilkS" user "Ref Des/Silkscreen Top")
		(7 "B.SilkS" user "Ref Des/Silkscreen Bottom")
		(1 "F.Mask" user "Board Geometry/Soldermask Top")
		(3 "B.Mask" user "Board Geometry/Soldermask Bottom")
		(17 "Dwgs.User" user "User.Drawings")
		(19 "Cmts.User" user "User.Comments")
		(21 "Eco1.User" user "User.Eco1")
		(23 "Eco2.User" user "User.Eco2")
		(25 "Edge.Cuts" user "Board Geometry/Outline")
		(27 "Margin" user)
		(31 "F.CrtYd" user "Package Geometry/Place Bound Top")
		(29 "B.CrtYd" user "Package Geometry/Place Bound Bottom")
		(35 "F.Fab" user "Ref Des/Assembly Top")
		(33 "B.Fab" user "Ref Des/Assembly Bottom")
	)
	(footprint ""
		(layer "B.Cu")
		(at 51.9938 -132.6388)
		(property "Reference" "C109"
			(at 0 0 0)
			(layer "B.SilkS")
			(hide yes)
			(effects
				(font
					(size 1.27 1.27)
				)
				(justify mirror)
			)
		)
		(property "Value" "SC1U16V3KX-5GP"
			(at 0 -2.8194 0)
			(unlocked yes)
			(layer "B.Fab")
			(hide yes)
			(effects
				(font
					(size 1.016 1.016)
					(thickness 0.1524)
				)
				(justify mirror)
			)
		)
		(property "Device Type" "C603H36"
			(at 0 -4.3434 0)
			(unlocked yes)
			(layer "B.Fab")
			(hide yes)
			(effects
				(font
					(size 1.016 1.016)
					(thickness 0.1524)
				)
				(justify mirror)
			)
		)
		(duplicate_pad_numbers_are_jumpers no)
		(fp_line
			(start -0.508 0)
			(end 0.508 0)
			(stroke
				(width 0.2032)
				(type default)
			)
			(layer "B.SilkS")
		)
		(fp_rect
			(start 0.5842 1.3335)
			(end -0.5842 -1.3335)
			(stroke
				(width 0)
				(type default)
			)
			(fill no)
			(layer "B.CrtYd")
		)
		(fp_rect
			(start 0.5842 1.3335)
			(end -0.5842 -1.3335)
			(stroke
				(width 0)
				(type default)
			)
			(fill no)
			(layer "B.Fab")
		)
		(pad "1" smd custom
			(at 0 -0.762 180)
			(size 0.2159 0.2159)
			(layers "B.Cu" "B.Mask" "B.Paste")
			(net "P1V15_STBY")
			(options
				(clearance outline)
				(anchor circle)
			)
			(primitives
				(gr_poly
					(pts
						(arc
							(start -0.3302 0.4318)
							(mid -0.402042 0.402042)
							(end -0.4318 0.3302)
						)
						(arc
							(start -0.4318 -0.3302)
							(mid -0.402042 -0.402042)
							(end -0.3302 -0.4318)
						)
						(arc
							(start 0.3302 -0.4318)
							(mid 0.402042 -0.402042)
							(end 0.4318 -0.3302)
						)
						(arc
							(start 0.4318 0.3302)
							(mid 0.402042 0.402042)
							(end 0.3302 0.4318)
						)
					)
					(width 0)
					(fill yes)
				)
			)
		)
		(pad "2" smd custom
			(at 0 0.762 180)
			(size 0.2159 0.2159)
			(layers "B.Cu" "B.Mask" "B.Paste")
			(net "GND")
			(options
				(clearance outline)
				(anchor circle)
			)
			(primitives
				(gr_poly
					(pts
						(arc
							(start -0.3302 0.4318)
							(mid -0.402042 0.402042)
							(end -0.4318 0.3302)
						)
						(arc
							(start -0.4318 -0.3302)
							(mid -0.402042 -0.402042)
							(end -0.3302 -0.4318)
						)
						(arc
							(start 0.3302 -0.4318)
							(mid 0.402042 -0.402042)
							(end 0.4318 -0.3302)
						)
						(arc
							(start 0.4318 0.3302)
							(mid 0.402042 0.402042)
							(end 0.3302 0.4318)
						)
					)
					(width 0)
					(fill yes)
				)
			)
		)
	)
	(footprint ""
		(layer "B.Cu")
		(at 195.6562 -69.5452 180)
		(property "Reference" "C384"
			(at 0 0 0)
			(layer "B.SilkS")
			(hide yes)
			(effects
				(font
					(size 1.27 1.27)
				)
				(justify mirror)
			)
		)
		(property "Value" "SC10U6D3V5KX-4GP"
			(at 0.0762 -6.1214 180)
			(unlocked yes)
			(layer "B.Fab")
			(hide yes)
			(effects
				(font
					(size 1.016 1.016)
					(thickness 0.1524)
				)
				(justify mirror)
			)
		)
		(property "Device Type" "C805H58"
			(at 0.0762 -8.1534 180)
			(unlocked yes)
			(layer "B.Fab")
			(hide yes)
			(effects
				(font
					(size 1.016 1.016)
					(thickness 0.1524)
				)
				(justify mirror)
			)
		)
		(duplicate_pad_numbers_are_jumpers no)
		(fp_line
			(start -0.635 0)
			(end 0.635 0)
			(stroke
				(width 0.508)
				(type default)
			)
			(layer "B.SilkS")
		)
		(fp_rect
			(start 0.9652 1.778)
			(end -0.9652 -1.778)
			(stroke
				(width 0)
				(type default)
			)
			(fill no)
			(layer "B.CrtYd")
		)
		(fp_poly
			(pts
				(xy 0.9652 -1.778) (xy -0.9652 -1.778) (xy -0.9652 1.778) (xy 0.9652 1.778)
			)
			(stroke
				(width 0)
				(type default)
			)
			(fill no)
			(layer "B.Fab")
		)
		(pad "1" smd rect
			(at 0 -0.9652)
			(size 1.397 1.143)
			(layers "B.Cu" "B.Mask" "B.Paste")
			(net "P0V975")
		)
		(pad "2" smd rect
			(at 0 0.9652)
			(size 1.397 1.143)
			(layers "B.Cu" "B.Mask" "B.Paste")
			(net "GND")
		)
	)
	(footprint ""
		(layer "B.Cu")
		(at 85.334348 -178.789584)
		(property "Reference" "R96"
			(at 0 0 0)
			(layer "B.SilkS")
			(hide yes)
			(effects
				(font
					(size 1.27 1.27)
				)
				(justify mirror)
			)
		)
		(property "Value" "0R2J-2-GP"
			(at -0.064008 -3.993896 0)
			(unlocked yes)
			(layer "B.Fab")
			(hide yes)
			(effects
				(font
					(size 1.016 1.016)
					(thickness 0.1524)
				)
				(justify mirror)
			)
		)
		(property "Device Type" "R402H16"
			(at -0.064008 -5.517896 0)
			(unlocked yes)
			(layer "B.Fab")
			(hide yes)
			(effects
				(font
					(size 1.016 1.016)
					(thickness 0.1524)
				)
				(justify mirror)
			)
		)
		(duplicate_pad_numbers_are_jumpers no)
		(fp_line
			(start -0.508 -0.9398)
			(end 0.508 -0.9398)
			(stroke
				(width 0.1524)
				(type default)
			)
			(layer "B.SilkS")
		)
		(fp_line
			(start 0.508 -0.9398)
			(end 0.508 0.9398)
			(stroke
				(width 0.1524)
				(type default)
			)
			(layer "B.SilkS")
		)
		(fp_rect
			(start 0.508 0.9398)
			(end -0.508 -0.9398)
			(stroke
				(width 0)
				(type default)
			)
			(fill no)
			(layer "B.CrtYd")
		)
		(fp_rect
			(start 0.508 0.9398)
			(end -0.508 -0.9398)
			(stroke
				(width 0)
				(type default)
			)
			(fill no)
			(layer "B.Fab")
		)
		(pad "1" smd custom
			(at 0 -0.4445 180)
			(size 0.1397 0.1397)
			(layers "B.Cu" "B.Mask" "B.Paste")
			(net "I2C_BMC_COMP_SDA_R")
			(options
				(clearance outline)
				(anchor circle)
			)
			(primitives
				(gr_poly
					(pts
						(arc
							(start -0.1778 0.2794)
							(mid -0.249642 0.249642)
							(end -0.2794 0.1778)
						)
						(arc
							(start -0.2794 -0.1778)
							(mid -0.249642 -0.249642)
							(end -0.1778 -0.2794)
						)
						(arc
							(start 0.1778 -0.2794)
							(mid 0.249642 -0.249642)
							(end 0.2794 -0.1778)
						)
						(arc
							(start 0.2794 0.1778)
							(mid 0.249642 0.249642)
							(end 0.1778 0.2794)
						)
					)
					(width 0)
					(fill yes)
				)
			)
		)
		(pad "2" smd custom
			(at 0 0.4445 180)
			(size 0.1397 0.1397)
			(layers "B.Cu" "B.Mask" "B.Paste")
			(net "I2C_BMC_COMP_SDA")
			(options
				(clearance outline)
				(anchor circle)
			)
			(primitives
				(gr_poly
					(pts
						(arc
							(start -0.1778 0.2794)
							(mid -0.249642 0.249642)
							(end -0.2794 0.1778)
						)
						(arc
							(start -0.2794 -0.1778)
							(mid -0.249642 -0.249642)
							(end -0.1778 -0.2794)
						)
						(arc
							(start 0.1778 -0.2794)
							(mid 0.249642 -0.249642)
							(end 0.2794 -0.1778)
						)
						(arc
							(start 0.2794 0.1778)
							(mid 0.249642 0.249642)
							(end 0.1778 0.2794)
						)
					)
					(width 0)
					(fill yes)
				)
			)
		)
	)
	(footprint ""
		(layer "B.Cu")
		(at 54.229 -162.1536 90)
		(property "Reference" "C117"
			(at 0 0 90)
			(layer "B.SilkS")
			(hide yes)
			(effects
				(font
					(size 1.27 1.27)
				)
				(justify mirror)
			)
		)
		(property "Value" "SCD1U25V2KX-2-GP"
			(at -1.1811 -2.7051 90)
			(unlocked yes)
			(layer "B.Fab")
			(hide yes)
			(effects
				(font
					(size 1.016 1.016)
					(thickness 0.1524)
				)
				(justify mirror)
			)
		)
		(property "Device Type" "C402H22"
			(at -1.1811 -4.2291 90)
			(unlocked yes)
			(layer "B.Fab")
			(hide yes)
			(effects
				(font
					(size 1.016 1.016)
					(thickness 0.1524)
				)
				(justify mirror)
			)
		)
		(duplicate_pad_numbers_are_jumpers no)
		(fp_rect
			(start 0.4318 0.9525)
			(end -0.4318 -0.9525)
			(stroke
				(width 0)
				(type default)
			)
			(fill no)
			(layer "B.CrtYd")
		)
		(fp_rect
			(start 0.4318 0.9525)
			(end -0.4318 -0.9525)
			(stroke
				(width 0)
				(type default)
			)
			(fill no)
			(layer "B.Fab")
		)
		(pad "1" smd custom
			(at 0 -0.4445 270)
			(size 0.1524 0.1524)
			(layers "B.Cu" "B.Mask" "B.Paste")
			(net "ADC_12V")
			(options
				(clearance outline)
				(anchor circle)
			)
			(primitives
				(gr_poly
					(pts
						(arc
							(start 0.3048 0.2032)
							(mid 0.275042 0.275042)
							(end 0.2032 0.3048)
						)
						(arc
							(start -0.2032 0.3048)
							(mid -0.275042 0.275042)
							(end -0.3048 0.2032)
						)
						(arc
							(start -0.3048 -0.2032)
							(mid -0.275042 -0.275042)
							(end -0.2032 -0.3048)
						)
						(arc
							(start 0.2032 -0.3048)
							(mid 0.275042 -0.275042)
							(end 0.3048 -0.2032)
						)
					)
					(width 0)
					(fill yes)
				)
			)
		)
		(pad "2" smd custom
			(at 0 0.4445 270)
			(size 0.1524 0.1524)
			(layers "B.Cu" "B.Mask" "B.Paste")
			(net "GND")
			(options
				(clearance outline)
				(anchor circle)
			)
			(primitives
				(gr_poly
					(pts
						(arc
							(start 0.3048 0.2032)
							(mid 0.275042 0.275042)
							(end 0.2032 0.3048)
						)
						(arc
							(start -0.2032 0.3048)
							(mid -0.275042 0.275042)
							(end -0.3048 0.2032)
						)
						(arc
							(start -0.3048 -0.2032)
							(mid -0.275042 -0.275042)
							(end -0.2032 -0.3048)
						)
						(arc
							(start 0.2032 -0.3048)
							(mid 0.275042 -0.275042)
							(end 0.3048 -0.2032)
						)
					)
					(width 0)
					(fill yes)
				)
			)
		)
	)
	(footprint ""
		(layer "B.Cu")
		(at 44.221908 -145.810732 -90)
		(property "Reference" "R141"
			(at 0 0 90)
			(layer "B.SilkS")
			(hide yes)
			(effects
				(font
					(size 1.27 1.27)
				)
				(justify mirror)
			)
		)
		(property "Value" "1KR2D-1-GP"
			(at -0.064008 -3.993896 270)
			(unlocked yes)
			(layer "B.Fab")
			(hide yes)
			(effects
				(font
					(size 1.016 1.016)
					(thickness 0.1524)
				)
				(justify mirror)
			)
		)
		(property "Device Type" "R402H16"
			(at -0.064008 -5.517896 270)
			(unlocked yes)
			(layer "B.Fab")
			(hide yes)
			(effects
				(font
					(size 1.016 1.016)
					(thickness 0.1524)
				)
				(justify mirror)
			)
		)
		(duplicate_pad_numbers_are_jumpers no)
		(fp_line
			(start -0.508 -0.9398)
			(end 0.508 -0.9398)
			(stroke
				(width 0.1524)
				(type default)
			)
			(layer "B.SilkS")
		)
		(fp_line
			(start 0.508 -0.9398)
			(end 0.508 0.9398)
			(stroke
				(width 0.1524)
				(type default)
			)
			(layer "B.SilkS")
		)
		(fp_rect
			(start 0.508 0.9398)
			(end -0.508 -0.9398)
			(stroke
				(width 0)
				(type default)
			)
			(fill no)
			(layer "B.CrtYd")
		)
		(fp_rect
			(start 0.508 0.9398)
			(end -0.508 -0.9398)
			(stroke
				(width 0)
				(type default)
			)
			(fill no)
			(layer "B.Fab")
		)
		(pad "1" smd custom
			(at 0 -0.4445 90)
			(size 0.1397 0.1397)
			(layers "B.Cu" "B.Mask" "B.Paste")
			(net "P1V2_STBY")
			(options
				(clearance outline)
				(anchor circle)
			)
			(primitives
				(gr_poly
					(pts
						(arc
							(start -0.1778 0.2794)
							(mid -0.249642 0.249642)
							(end -0.2794 0.1778)
						)
						(arc
							(start -0.2794 -0.1778)
							(mid -0.249642 -0.249642)
							(end -0.1778 -0.2794)
						)
						(arc
							(start 0.1778 -0.2794)
							(mid 0.249642 -0.249642)
							(end 0.2794 -0.1778)
						)
						(arc
							(start 0.2794 0.1778)
							(mid 0.249642 0.249642)
							(end 0.1778 0.2794)
						)
					)
					(width 0)
					(fill yes)
				)
			)
		)
		(pad "2" smd custom
			(at 0 0.4445 90)
			(size 0.1397 0.1397)
			(layers "B.Cu" "B.Mask" "B.Paste")
			(net "DDR_VREF")
			(options
				(clearance outline)
				(anchor circle)
			)
			(primitives
				(gr_poly
					(pts
						(arc
							(start -0.1778 0.2794)
							(mid -0.249642 0.249642)
							(end -0.2794 0.1778)
						)
						(arc
							(start -0.2794 -0.1778)
							(mid -0.249642 -0.249642)
							(end -0.1778 -0.2794)
						)
						(arc
							(start 0.1778 -0.2794)
							(mid 0.249642 -0.249642)
							(end 0.2794 -0.1778)
						)
						(arc
							(start 0.2794 0.1778)
							(mid 0.249642 0.249642)
							(end 0.1778 0.2794)
						)
					)
					(width 0)
					(fill yes)
				)
			)
		)
	)
	(footprint ""
		(layer "B.Cu")
		(at 206.737712 -64.430656 90)
		(property "Reference" "R598"
			(at 0 0 90)
			(layer "B.SilkS")
			(hide yes)
			(effects
				(font
					(size 1.27 1.27)
				)
				(justify mirror)
			)
		)
		(property "Value" "10KR2F-2-GP"
			(at -0.064008 -3.993896 90)
			(unlocked yes)
			(layer "B.Fab")
			(hide yes)
			(effects
				(font
					(size 1.016 1.016)
					(thickness 0.1524)
				)
				(justify mirror)
			)
		)
		(property "Device Type" "R402H16"
			(at -0.064008 -5.517896 90)
			(unlocked yes)
			(layer "B.Fab")
			(hide yes)
			(effects
				(font
					(size 1.016 1.016)
					(thickness 0.1524)
				)
				(justify mirror)
			)
		)
		(duplicate_pad_numbers_are_jumpers no)
		(fp_line
			(start 0.508 -0.9398)
			(end 0.508 0.9398)
			(stroke
				(width 0.1524)
				(type default)
			)
			(layer "B.SilkS")
		)
		(fp_line
			(start -0.508 -0.9398)
			(end 0.508 -0.9398)
			(stroke
				(width 0.1524)
				(type default)
			)
			(layer "B.SilkS")
		)
		(fp_rect
			(start 0.508 0.9398)
			(end -0.508 -0.9398)
			(stroke
				(width 0)
				(type default)
			)
			(fill no)
			(layer "B.CrtYd")
		)
		(fp_rect
			(start 0.508 0.9398)
			(end -0.508 -0.9398)
			(stroke
				(width 0)
				(type default)
			)
			(fill no)
			(layer "B.Fab")
		)
		(pad "1" smd custom
			(at 0 -0.4445 270)
			(size 0.1397 0.1397)
			(layers "B.Cu" "B.Mask" "B.Paste")
			(net "IOC_SIO_BLINK")
			(options
				(clearance outline)
				(anchor circle)
			)
			(primitives
				(gr_poly
					(pts
						(arc
							(start -0.1778 0.2794)
							(mid -0.249642 0.249642)
							(end -0.2794 0.1778)
						)
						(arc
							(start -0.2794 -0.1778)
							(mid -0.249642 -0.249642)
							(end -0.1778 -0.2794)
						)
						(arc
							(start 0.1778 -0.2794)
							(mid 0.249642 -0.249642)
							(end 0.2794 -0.1778)
						)
						(arc
							(start 0.2794 0.1778)
							(mid 0.249642 0.249642)
							(end 0.1778 0.2794)
						)
					)
					(width 0)
					(fill yes)
				)
			)
		)
		(pad "2" smd custom
			(at 0 0.4445 270)
			(size 0.1397 0.1397)
			(layers "B.Cu" "B.Mask" "B.Paste")
			(net "GND")
			(options
				(clearance outline)
				(anchor circle)
			)
			(primitives
				(gr_poly
					(pts
						(arc
							(start -0.1778 0.2794)
							(mid -0.249642 0.249642)
							(end -0.2794 0.1778)
						)
						(arc
							(start -0.2794 -0.1778)
							(mid -0.249642 -0.249642)
							(end -0.1778 -0.2794)
						)
						(arc
							(start 0.1778 -0.2794)
							(mid 0.249642 -0.249642)
							(end 0.2794 -0.1778)
						)
						(arc
							(start 0.2794 0.1778)
							(mid 0.249642 0.249642)
							(end 0.1778 0.2794)
						)
					)
					(width 0)
					(fill yes)
				)
			)
		)
	)
	(footprint ""
		(layer "B.Cu")
		(at 189.2554 -64.8208 90)
		(property "Reference" "C412"
			(at 0 0 90)
			(layer "B.SilkS")
			(hide yes)
			(effects
				(font
					(size 1.27 1.27)
				)
				(justify mirror)
			)
		)
		(property "Value" "SCD1U6D3V1KX-GP"
			(at 2.8321 -1.7399 90)
			(unlocked yes)
			(layer "B.Fab")
			(hide yes)
			(effects
				(font
					(size 1.016 1.016)
					(thickness 0.1524)
				)
				(justify mirror)
			)
		)
		(property "Device Type" "C0201H13"
			(at 2.8321 -3.2639 90)
			(unlocked yes)
			(layer "B.Fab")
			(hide yes)
			(effects
				(font
					(size 1.016 1.016)
					(thickness 0.1524)
				)
				(justify mirror)
			)
		)
		(duplicate_pad_numbers_are_jumpers no)
		(fp_rect
			(start 0.2794 0.6477)
			(end -0.2794 -0.6477)
			(stroke
				(width 0)
				(type default)
			)
			(fill no)
			(layer "B.CrtYd")
		)
		(fp_rect
			(start 0.2794 0.6477)
			(end -0.2794 -0.6477)
			(stroke
				(width 0)
				(type default)
			)
			(fill no)
			(layer "B.Fab")
		)
		(pad "1" smd custom
			(at 0 -0.2794 270)
			(size 0.0762 0.0762)
			(layers "B.Cu" "B.Mask" "B.Paste")
			(net "P0V975")
			(options
				(clearance outline)
				(anchor circle)
			)
			(primitives
				(gr_poly
					(pts
						(arc
							(start 0.1524 0.127)
							(mid 0.137521 0.162921)
							(end 0.1016 0.1778)
						)
						(arc
							(start -0.1016 0.1778)
							(mid -0.137521 0.162921)
							(end -0.1524 0.127)
						)
						(arc
							(start -0.1524 -0.127)
							(mid -0.137521 -0.162921)
							(end -0.1016 -0.1778)
						)
						(arc
							(start 0.1016 -0.1778)
							(mid 0.137521 -0.162921)
							(end 0.1524 -0.127)
						)
					)
					(width 0)
					(fill yes)
				)
			)
		)
		(pad "2" smd custom
			(at 0 0.2794 270)
			(size 0.0762 0.0762)
			(layers "B.Cu" "B.Mask" "B.Paste")
			(net "GND")
			(options
				(clearance outline)
				(anchor circle)
			)
			(primitives
				(gr_poly
					(pts
						(arc
							(start 0.1524 0.127)
							(mid 0.137521 0.162921)
							(end 0.1016 0.1778)
						)
						(arc
							(start -0.1016 0.1778)
							(mid -0.137521 0.162921)
							(end -0.1524 0.127)
						)
						(arc
							(start -0.1524 -0.127)
							(mid -0.137521 -0.162921)
							(end -0.1016 -0.1778)
						)
						(arc
							(start 0.1016 -0.1778)
							(mid 0.137521 -0.162921)
							(end 0.1524 -0.127)
						)
					)
					(width 0)
					(fill yes)
				)
			)
		)
	)
	(footprint ""
		(layer "B.Cu")
		(at 189.5983 -68.3006 -90)
		(property "Reference" "C429"
			(at 0 0 90)
			(layer "B.SilkS")
			(hide yes)
			(effects
				(font
					(size 1.27 1.27)
				)
				(justify mirror)
			)
		)
		(property "Value" "SC1KP50V2KX-1GP"
			(at -1.1811 -2.7051 270)
			(unlocked yes)
			(layer "B.Fab")
			(hide yes)
			(effects
				(font
					(size 1.016 1.016)
					(thickness 0.1524)
				)
				(justify mirror)
			)
		)
		(property "Device Type" "C402H22"
			(at -1.1811 -4.2291 270)
			(unlocked yes)
			(layer "B.Fab")
			(hide yes)
			(effects
				(font
					(size 1.016 1.016)
					(thickness 0.1524)
				)
				(justify mirror)
			)
		)
		(duplicate_pad_numbers_are_jumpers no)
		(fp_rect
			(start 0.4318 0.9525)
			(end -0.4318 -0.9525)
			(stroke
				(width 0)
				(type default)
			)
			(fill no)
			(layer "B.CrtYd")
		)
		(fp_rect
			(start 0.4318 0.9525)
			(end -0.4318 -0.9525)
			(stroke
				(width 0)
				(type default)
			)
			(fill no)
			(layer "B.Fab")
		)
		(pad "1" smd custom
			(at 0 -0.4445 90)
			(size 0.1524 0.1524)
			(layers "B.Cu" "B.Mask" "B.Paste")
			(net "P0V975")
			(options
				(clearance outline)
				(anchor circle)
			)
			(primitives
				(gr_poly
					(pts
						(arc
							(start 0.3048 0.2032)
							(mid 0.275042 0.275042)
							(end 0.2032 0.3048)
						)
						(arc
							(start -0.2032 0.3048)
							(mid -0.275042 0.275042)
							(end -0.3048 0.2032)
						)
						(arc
							(start -0.3048 -0.2032)
							(mid -0.275042 -0.275042)
							(end -0.2032 -0.3048)
						)
						(arc
							(start 0.2032 -0.3048)
							(mid 0.275042 -0.275042)
							(end 0.3048 -0.2032)
						)
					)
					(width 0)
					(fill yes)
				)
			)
		)
		(pad "2" smd custom
			(at 0 0.4445 90)
			(size 0.1524 0.1524)
			(layers "B.Cu" "B.Mask" "B.Paste")
			(net "GND")
			(options
				(clearance outline)
				(anchor circle)
			)
			(primitives
				(gr_poly
					(pts
						(arc
							(start 0.3048 0.2032)
							(mid 0.275042 0.275042)
							(end 0.2032 0.3048)
						)
						(arc
							(start -0.2032 0.3048)
							(mid -0.275042 0.275042)
							(end -0.3048 0.2032)
						)
						(arc
							(start -0.3048 -0.2032)
							(mid -0.275042 -0.275042)
							(end -0.2032 -0.3048)
						)
						(arc
							(start 0.2032 -0.3048)
							(mid 0.275042 -0.275042)
							(end 0.3048 -0.2032)
						)
					)
					(width 0)
					(fill yes)
				)
			)
		)
	)
)
